# S9S_MB_2U (Grand Teton) — schematic netlist excerpt (pin names and nets, part order shuffled) for the footprints in the layout excerpt that follows; sources: Cadence DE-HDL packaged netlist, KiCad conversion of 03242023_DA0F0TMBIJ0_F0T_Motherboard_J_brd_V01_OCP.brd

PR4007  Q_RES  10K 1% CHIP  pkg 0402LF  page 242 : A = P12V_SCM_FLTB_N ; B = P3V3_AUX
PC193  Q_CAP  100NF 50V 10% X7R  pkg C0402  page 275 : A = SW_PVCCINFAON_CPU0_BOOT1_R ; B = SW_PVCCINFAON_CPU0_BOOTR1

(kicad_pcb
	(version 20260206)
	(generator "pcbnew")
	(generator_version "10.0")
	(general
		(thickness 1.6)
		(legacy_teardrops no)
	)
	(paper "A4")
	(title_block
		(title "03242023_DA0F0TMBIJ0_F0T_Motherboard_J_brd_V01_OCP.brd")
		(comment 1 "Grand Teton / footprints 3082-3083 of 6105")
	)
	(layers
		(0 "F.Cu" signal "TOP")
		(4 "In1.Cu" signal "GND")
		(6 "In2.Cu" signal "IN1")
		(8 "In3.Cu" signal "GND1")
		(10 "In4.Cu" signal "IN2")
		(12 "In5.Cu" signal "GND2")
		(14 "In6.Cu" signal "IN3")
		(16 "In7.Cu" signal "GND3")
		(18 "In8.Cu" signal "VCC")
		(20 "In9.Cu" signal "VCC1")
		(22 "In10.Cu" signal "GND4")
		(24 "In11.Cu" signal "IN4")
		(26 "In12.Cu" signal "GND5")
		(28 "In13.Cu" signal "IN5")
		(30 "In14.Cu" signal "GND6")
		(32 "In15.Cu" signal "IN6")
		(34 "In16.Cu" signal "GND7")
		(2 "B.Cu" signal "BOTTOM")
		(9 "F.Adhes" user "F.Adhesive")
		(11 "B.Adhes" user "B.Adhesive")
		(13 "F.Paste" user "Package Geometry/Pastemask Top")
		(15 "B.Paste" user "Package Geometry/Pastemask Bottom")
		(5 "F.SilkS" user "Ref Des/Silkscreen Top")
		(7 "B.SilkS" user "Ref Des/Silkscreen Bottom")
		(1 "F.Mask" user "Board Geometry/Soldermask Top")
		(3 "B.Mask" user "Board Geometry/Soldermask Bottom")
		(17 "Dwgs.User" user "User.Drawings")
		(19 "Cmts.User" user "User.Comments")
		(21 "Eco1.User" user "User.Eco1")
		(23 "Eco2.User" user "User.Eco2")
		(25 "Edge.Cuts" user "Board Geometry/Outline")
		(27 "Margin" user)
		(31 "F.CrtYd" user "Package Geometry/Place Bound Top")
		(29 "B.CrtYd" user "Package Geometry/Place Bound Bottom")
		(35 "F.Fab" user "Ref Des/Assembly Top")
		(33 "B.Fab" user "Ref Des/Assembly Bottom")
	)
	(footprint ""
		(layer "F.Cu")
		(at 173.216062 -30.370272 180)
		(property "Reference" "PR4007"
			(at 0 0 180)
			(layer "F.SilkS")
			(hide yes)
			(effects
				(font
					(size 1.27 1.27)
				)
			)
		)
		(property "Value" ""
			(at 0 0 180)
			(layer "F.Fab")
			(effects
				(font
					(size 1.27 1.27)
				)
			)
		)
		(duplicate_pad_numbers_are_jumpers no)
		(fp_line
			(start 0.7874 0.4064)
			(end -0.7874 0.4064)
			(stroke
				(width 0.1524)
				(type default)
			)
			(layer "F.SilkS")
		)
		(fp_line
			(start 0.7874 -0.4064)
			(end 0.7874 0.4064)
			(stroke
				(width 0.1524)
				(type default)
			)
			(layer "F.SilkS")
		)
		(fp_line
			(start -0.7874 0.4064)
			(end -0.7874 -0.4064)
			(stroke
				(width 0.1524)
				(type default)
			)
			(layer "F.SilkS")
		)
		(fp_line
			(start -0.7874 -0.4064)
			(end 0.7874 -0.4064)
			(stroke
				(width 0.1524)
				(type default)
			)
			(layer "F.SilkS")
		)
		(fp_line
			(start 0.67945 0.3048)
			(end 0.120396 0.3048)
			(stroke
				(width 0.1)
				(type default)
			)
			(layer "F.Fab")
		)
		(fp_line
			(start 0.67945 -0.3048)
			(end 0.67945 0.3048)
			(stroke
				(width 0.1)
				(type default)
			)
			(layer "F.Fab")
		)
		(fp_line
			(start 0.12065 -0.2794)
			(end 0.12065 -0.3048)
			(stroke
				(width 0.1)
				(type default)
			)
			(layer "F.Fab")
		)
		(fp_line
			(start 0.12065 -0.3048)
			(end 0.67945 -0.3048)
			(stroke
				(width 0.1)
				(type default)
			)
			(layer "F.Fab")
		)
		(fp_line
			(start 0.120396 0.3048)
			(end 0.120396 0.2794)
			(stroke
				(width 0.1)
				(type default)
			)
			(layer "F.Fab")
		)
		(fp_line
			(start 0.120396 0.2794)
			(end -0.12065 0.2794)
			(stroke
				(width 0.1)
				(type default)
			)
			(layer "F.Fab")
		)
		(fp_line
			(start -0.12065 0.3048)
			(end -0.67945 0.3048)
			(stroke
				(width 0.1)
				(type default)
			)
			(layer "F.Fab")
		)
		(fp_line
			(start -0.12065 0.2794)
			(end -0.12065 0.3048)
			(stroke
				(width 0.1)
				(type default)
			)
			(layer "F.Fab")
		)
		(fp_line
			(start -0.12065 -0.2794)
			(end 0.12065 -0.2794)
			(stroke
				(width 0.1)
				(type default)
			)
			(layer "F.Fab")
		)
		(fp_line
			(start -0.12065 -0.305054)
			(end -0.12065 -0.2794)
			(stroke
				(width 0.1)
				(type default)
			)
			(layer "F.Fab")
		)
		(fp_line
			(start -0.67945 0.3048)
			(end -0.67945 -0.305054)
			(stroke
				(width 0.1)
				(type default)
			)
			(layer "F.Fab")
		)
		(fp_line
			(start -0.67945 -0.305054)
			(end -0.12065 -0.305054)
			(stroke
				(width 0.1)
				(type default)
			)
			(layer "F.Fab")
		)
		(pad "1" smd circle
			(at -0.40005 0 180)
			(size 0 0)
			(layers "F.Cu" "F.Mask" "F.Paste")
			(net "P12V_SCM_FLTB_N")
		)
		(pad "2" smd circle
			(at 0.40005 0 180)
			(size 0 0)
			(layers "F.Cu" "F.Mask" "F.Paste")
			(net "P3V3_AUX")
		)
	)
	(footprint ""
		(layer "F.Cu")
		(at 420.4716 -169.088562 180)
		(property "Reference" "PC193"
			(at 0 0 180)
			(layer "F.SilkS")
			(hide yes)
			(effects
				(font
					(size 1.27 1.27)
				)
			)
		)
		(property "Value" ""
			(at 0 0 180)
			(layer "F.Fab")
			(effects
				(font
					(size 1.27 1.27)
				)
			)
		)
		(duplicate_pad_numbers_are_jumpers no)
		(fp_line
			(start 0.7874 0.4064)
			(end -0.7874 0.4064)
			(stroke
				(width 0.1524)
				(type default)
			)
			(layer "F.SilkS")
		)
		(fp_line
			(start 0.7874 -0.4064)
			(end 0.7874 0.4064)
			(stroke
				(width 0.1524)
				(type default)
			)
			(layer "F.SilkS")
		)
		(fp_line
			(start -0.7874 0.4064)
			(end -0.7874 -0.4064)
			(stroke
				(width 0.1524)
				(type default)
			)
			(layer "F.SilkS")
		)
		(fp_line
			(start -0.7874 -0.4064)
			(end 0.7874 -0.4064)
			(stroke
				(width 0.1524)
				(type default)
			)
			(layer "F.SilkS")
		)
		(fp_line
			(start 0.67945 0.3048)
			(end 0.120396 0.3048)
			(stroke
				(width 0.1)
				(type default)
			)
			(layer "F.Fab")
		)
		(fp_line
			(start 0.67945 -0.3048)
			(end 0.67945 0.3048)
			(stroke
				(width 0.1)
				(type default)
			)
			(layer "F.Fab")
		)
		(fp_line
			(start 0.12065 -0.2794)
			(end 0.12065 -0.3048)
			(stroke
				(width 0.1)
				(type default)
			)
			(layer "F.Fab")
		)
		(fp_line
			(start 0.12065 -0.3048)
			(end 0.67945 -0.3048)
			(stroke
				(width 0.1)
				(type default)
			)
			(layer "F.Fab")
		)
		(fp_line
			(start 0.120396 0.3048)
			(end 0.120396 0.2794)
			(stroke
				(width 0.1)
				(type default)
			)
			(layer "F.Fab")
		)
		(fp_line
			(start 0.120396 0.2794)
			(end -0.12065 0.2794)
			(stroke
				(width 0.1)
				(type default)
			)
			(layer "F.Fab")
		)
		(fp_line
			(start -0.12065 0.3048)
			(end -0.67945 0.3048)
			(stroke
				(width 0.1)
				(type default)
			)
			(layer "F.Fab")
		)
		(fp_line
			(start -0.12065 0.2794)
			(end -0.12065 0.3048)
			(stroke
				(width 0.1)
				(type default)
			)
			(layer "F.Fab")
		)
		(fp_line
			(start -0.12065 -0.2794)
			(end 0.12065 -0.2794)
			(stroke
				(width 0.1)
				(type default)
			)
			(layer "F.Fab")
		)
		(fp_line
			(start -0.12065 -0.305054)
			(end -0.12065 -0.2794)
			(stroke
				(width 0.1)
				(type default)
			)
			(layer "F.Fab")
		)
		(fp_line
			(start -0.67945 0.3048)
			(end -0.67945 -0.305054)
			(stroke
				(width 0.1)
				(type default)
			)
			(layer "F.Fab")
		)
		(fp_line
			(start -0.67945 -0.305054)
			(end -0.12065 -0.305054)
			(stroke
				(width 0.1)
				(type default)
			)
			(layer "F.Fab")
		)
		(pad "1" smd circle
			(at -0.40005 0 180)
			(size 0 0)
			(layers "F.Cu" "F.Mask" "F.Paste")
			(net "SW_PVCCINFAON_CPU0_BOOT1_R")
		)
		(pad "2" smd circle
			(at 0.40005 0 180)
			(size 0 0)
			(layers "F.Cu" "F.Mask" "F.Paste")
			(net "SW_PVCCINFAON_CPU0_BOOTR1")
		)
	)
)
